(kicad_pcb
	(version 20241229)
	(generator "pcbnew")
	(generator_version "9.0")
	(general
		(thickness 1.294)
		(legacy_teardrops no)
	)
	(paper "A3")
	(title_block
		(title "Kintex 410T devboard")
		(date "2024-04-03")
		(rev "1.1.2")
		(comment 9 "footprints 348-354 of 975")
	)
	(layers
		(0 "F.Cu" mixed)
		(4 "In1.Cu" power)
		(6 "In2.Cu" power)
		(8 "In3.Cu" mixed)
		(10 "In4.Cu" power)
		(12 "In5.Cu" mixed)
		(14 "In6.Cu" power)
		(16 "In7.Cu" mixed)
		(18 "In8.Cu" power)
		(2 "B.Cu" mixed)
		(9 "F.Adhes" user "F.Adhesive")
		(11 "B.Adhes" user "B.Adhesive")
		(13 "F.Paste" user)
		(15 "B.Paste" user)
		(5 "F.SilkS" user "F.Silkscreen")
		(7 "B.SilkS" user "B.Silkscreen")
		(1 "F.Mask" user)
		(3 "B.Mask" user)
		(17 "Dwgs.User" user "User.Drawings")
		(19 "Cmts.User" user "User.Comments")
		(21 "Eco1.User" user "User.Eco1")
		(23 "Eco2.User" user "User.Eco2")
		(25 "Edge.Cuts" user)
		(27 "Margin" user)
		(31 "F.CrtYd" user "F.Courtyard")
		(29 "B.CrtYd" user "B.Courtyard")
		(35 "F.Fab" user)
		(33 "B.Fab" user)
	)
	(footprint "antmicro-footprints:R_0402_1005Metric"
		(layer "F.Cu")
		(at 235.915 118.5 180)
		(descr "Resistor SMD 0402")
		(tags "resistor SMD 0402")
		(property "Reference" "R79"
			(at -0.735 -0.35 180)
			(layer "F.SilkS")
			(effects
				(font
					(size 0.7 0.7)
					(thickness 0.15)
				)
				(justify left bottom)
			)
		)
		(property "Value" "R_0R_0402"
			(at 0 1.4 180)
			(layer "F.Fab")
			(effects
				(font
					(size 0.7 0.7)
					(thickness 0.15)
				)
				(justify left bottom)
			)
		)
		(property "Description" "SMD Chip Resistor, Jumper, 0 ohm, 100 mW, 0402 [1005 Metric], Thick Film, General Purpose"
			(at 0 0 180)
			(layer "F.Fab")
			(hide yes)
			(effects
				(font
					(size 1.27 1.27)
					(thickness 0.15)
				)
			)
		)
		(property "Author" "Antmicro"
			(at 471.83 237 0)
			(layer "F.Fab")
			(hide yes)
			(effects
				(font
					(size 1 1)
					(thickness 0.15)
				)
			)
		)
		(property "Current" "1A"
			(at 471.83 237 0)
			(layer "F.Fab")
			(hide yes)
			(effects
				(font
					(size 1 1)
					(thickness 0.15)
				)
			)
		)
		(property "License" "Apache-2.0"
			(at 471.83 237 0)
			(layer "F.Fab")
			(hide yes)
			(effects
				(font
					(size 1 1)
					(thickness 0.15)
				)
			)
		)
		(property "MPN" "ERJ2GE0R00X"
			(at 471.83 237 0)
			(layer "F.Fab")
			(hide yes)
			(effects
				(font
					(size 1 1)
					(thickness 0.15)
				)
			)
		)
		(property "Manufacturer" "Panasonic"
			(at 471.83 237 0)
			(layer "F.Fab")
			(hide yes)
			(effects
				(font
					(size 1 1)
					(thickness 0.15)
				)
			)
		)
		(property "Tolerance" ""
			(at 471.83 237 0)
			(layer "F.Fab")
			(hide yes)
			(effects
				(font
					(size 1 1)
					(thickness 0.15)
				)
			)
		)
		(property "Val" "0R"
			(at 471.83 237 0)
			(layer "F.Fab")
			(hide yes)
			(effects
				(font
					(size 1 1)
					(thickness 0.15)
				)
			)
		)
		(sheetname "SPI Flash + SD Card")
		(sheetfile "spi-flash.kicad_sch")
		(attr smd)
		(fp_rect
			(start -0.925 -0.47)
			(end 0.925 0.47)
			(stroke
				(width 0.05)
				(type default)
			)
			(fill no)
			(layer "F.CrtYd")
		)
		(fp_rect
			(start -0.5 -0.25)
			(end 0.5 0.25)
			(stroke
				(width 0.15)
				(type solid)
			)
			(fill no)
			(layer "F.Fab")
		)
		(pad "1" smd roundrect
			(at -0.48 0 180)
			(size 0.59 0.64)
			(layers "F.Cu" "F.Mask" "F.Paste")
			(roundrect_rratio 0.25)
			(net 398 "/FPGA Bank 14 & 15/SYSTEM_FLASH.DQ3")
			(pintype "passive")
		)
		(pad "2" smd roundrect
			(at 0.48 0 180)
			(size 0.59 0.64)
			(layers "F.Cu" "F.Mask" "F.Paste")
			(roundrect_rratio 0.25)
			(net 899 "/SPI Flash + SD Card/SYSTEM_FLASH_DQ3")
			(pintype "passive")
		)
	)
	(footprint "antmicro-footprints:R_0402_1005Metric"
		(layer "F.Cu")
		(at 252.899 96)
		(descr "Resistor SMD 0402")
		(tags "resistor SMD 0402")
		(property "Reference" "R345"
			(at -1.499 -0.5 0)
			(layer "F.SilkS")
			(effects
				(font
					(size 0.7 0.7)
					(thickness 0.15)
				)
				(justify left bottom)
			)
		)
		(property "Value" "R_10k_0402"
			(at 0 1.4 0)
			(layer "F.Fab")
			(effects
				(font
					(size 0.7 0.7)
					(thickness 0.15)
				)
				(justify left bottom)
			)
		)
		(property "Description" "SMD Chip Resistor, 10 kohm, ± 1%, 62.5 mW, 0402 [1005 Metric], Thick Film, General Purpose"
			(at 0 0 0)
			(layer "F.Fab")
			(hide yes)
			(effects
				(font
					(size 1.27 1.27)
					(thickness 0.15)
				)
			)
		)
		(property "Author" "Antmicro"
			(at 0 0 0)
			(layer "F.Fab")
			(hide yes)
			(effects
				(font
					(size 1 1)
					(thickness 0.15)
				)
			)
		)
		(property "License" "Apache-2.0"
			(at 0 0 0)
			(layer "F.Fab")
			(hide yes)
			(effects
				(font
					(size 1 1)
					(thickness 0.15)
				)
			)
		)
		(property "MPN" "CR0402-FX-1002GLF"
			(at 0 0 0)
			(layer "F.Fab")
			(hide yes)
			(effects
				(font
					(size 1 1)
					(thickness 0.15)
				)
			)
		)
		(property "Manufacturer" "Bourns"
			(at 0 0 0)
			(layer "F.Fab")
			(hide yes)
			(effects
				(font
					(size 1 1)
					(thickness 0.15)
				)
			)
		)
		(property "Tolerance" "1%"
			(at 0 0 0)
			(layer "F.Fab")
			(hide yes)
			(effects
				(font
					(size 1 1)
					(thickness 0.15)
				)
			)
		)
		(property "Val" "10k"
			(at 0 0 0)
			(layer "F.Fab")
			(hide yes)
			(effects
				(font
					(size 1 1)
					(thickness 0.15)
				)
			)
		)
		(sheetname "USB PHY")
		(sheetfile "usb-phy.kicad_sch")
		(attr smd)
		(fp_rect
			(start -0.925 -0.47)
			(end 0.925 0.47)
			(stroke
				(width 0.05)
				(type default)
			)
			(fill no)
			(layer "F.CrtYd")
		)
		(fp_rect
			(start -0.5 -0.25)
			(end 0.5 0.25)
			(stroke
				(width 0.15)
				(type solid)
			)
			(fill no)
			(layer "F.Fab")
		)
		(pad "1" smd roundrect
			(at -0.48 0)
			(size 0.59 0.64)
			(layers "F.Cu" "F.Mask" "F.Paste")
			(roundrect_rratio 0.25)
			(net 583 "/USB PHY/USB_HOST_VBUS_EN")
			(pintype "passive")
		)
		(pad "2" smd roundrect
			(at 0.48 0)
			(size 0.59 0.64)
			(layers "F.Cu" "F.Mask" "F.Paste")
			(roundrect_rratio 0.25)
			(net 1 "GND")
			(pintype "passive")
		)
	)
	(footprint "antmicro-footprints:TP_SMD_0.75mm"
		(layer "F.Cu")
		(at 164.5 170.2)
		(property "Reference" "TP6"
			(at 0.3 0.35 0)
			(layer "F.SilkS")
			(effects
				(font
					(size 0.7 0.7)
					(thickness 0.15)
				)
				(justify left bottom)
			)
		)
		(property "Value" "TP_0.75mm_SMD"
			(at 0 1.2 0)
			(layer "F.Fab")
			(effects
				(font
					(size 0.7 0.7)
					(thickness 0.15)
				)
				(justify left bottom)
			)
		)
		(property "Description" "SMT test point"
			(at 0 0 0)
			(layer "F.Fab")
			(hide yes)
			(effects
				(font
					(size 1.27 1.27)
					(thickness 0.15)
				)
			)
		)
		(property "Author" "Antmicro"
			(at 0 0 0)
			(layer "F.Fab")
			(hide yes)
			(effects
				(font
					(size 1 1)
					(thickness 0.15)
				)
			)
		)
		(property "License" "Apache-2.0"
			(at 0 0 0)
			(layer "F.Fab")
			(hide yes)
			(effects
				(font
					(size 1 1)
					(thickness 0.15)
				)
			)
		)
		(property "MPN" ""
			(at 0 0 0)
			(layer "F.Fab")
			(hide yes)
			(effects
				(font
					(size 1 1)
					(thickness 0.15)
				)
			)
		)
		(property "Manufacturer" ""
			(at 0 0 0)
			(layer "F.Fab")
			(hide yes)
			(effects
				(font
					(size 1 1)
					(thickness 0.15)
				)
			)
		)
		(sheetname "DC-DC Converters")
		(sheetfile "dc-dc.kicad_sch")
		(attr exclude_from_pos_files)
		(pad "1" smd circle
			(at 0 0)
			(size 0.75 0.75)
			(layers "F.Cu" "F.Mask")
			(net 1394 "/I2C.QDCDC1_SCL")
			(pinfunction "1")
			(pintype "passive")
		)
	)
	(footprint "antmicro-footprints:R_0402_1005Metric"
		(layer "F.Cu")
		(at 207.64 81.74)
		(descr "Resistor SMD 0402")
		(tags "resistor SMD 0402")
		(property "Reference" "R5"
			(at -1.34 1.26 0)
			(layer "F.SilkS")
			(effects
				(font
					(size 0.7 0.7)
					(thickness 0.15)
				)
				(justify left bottom)
			)
		)
		(property "Value" "R_10k_0402"
			(at 0 1.4 0)
			(layer "F.Fab")
			(effects
				(font
					(size 0.7 0.7)
					(thickness 0.15)
				)
				(justify left bottom)
			)
		)
		(property "Description" "SMD Chip Resistor, 10 kohm, ± 1%, 62.5 mW, 0402 [1005 Metric], Thick Film, General Purpose"
			(at 0 0 0)
			(layer "F.Fab")
			(hide yes)
			(effects
				(font
					(size 1.27 1.27)
					(thickness 0.15)
				)
			)
		)
		(property "Author" "Antmicro"
			(at 0 0 0)
			(layer "F.Fab")
			(hide yes)
			(effects
				(font
					(size 1 1)
					(thickness 0.15)
				)
			)
		)
		(property "License" "Apache-2.0"
			(at 0 0 0)
			(layer "F.Fab")
			(hide yes)
			(effects
				(font
					(size 1 1)
					(thickness 0.15)
				)
			)
		)
		(property "MPN" "CR0402-FX-1002GLF"
			(at 0 0 0)
			(layer "F.Fab")
			(hide yes)
			(effects
				(font
					(size 1 1)
					(thickness 0.15)
				)
			)
		)
		(property "Manufacturer" "Bourns"
			(at 0 0 0)
			(layer "F.Fab")
			(hide yes)
			(effects
				(font
					(size 1 1)
					(thickness 0.15)
				)
			)
		)
		(property "Tolerance" "1%"
			(at 0 0 0)
			(layer "F.Fab")
			(hide yes)
			(effects
				(font
					(size 1 1)
					(thickness 0.15)
				)
			)
		)
		(property "Val" "10k"
			(at 0 0 0)
			(layer "F.Fab")
			(hide yes)
			(effects
				(font
					(size 1 1)
					(thickness 0.15)
				)
			)
		)
		(sheetname "FPGA Config")
		(sheetfile "fpga-config.kicad_sch")
		(attr smd)
		(fp_rect
			(start -0.925 -0.47)
			(end 0.925 0.47)
			(stroke
				(width 0.05)
				(type default)
			)
			(fill no)
			(layer "F.CrtYd")
		)
		(fp_rect
			(start -0.5 -0.25)
			(end 0.5 0.25)
			(stroke
				(width 0.15)
				(type solid)
			)
			(fill no)
			(layer "F.Fab")
		)
		(pad "1" smd roundrect
			(at -0.48 0)
			(size 0.59 0.64)
			(layers "F.Cu" "F.Mask" "F.Paste")
			(roundrect_rratio 0.25)
			(net 246 "/FPGA Config/DONE")
			(pintype "passive")
		)
		(pad "2" smd roundrect
			(at 0.48 0)
			(size 0.59 0.64)
			(layers "F.Cu" "F.Mask" "F.Paste")
			(roundrect_rratio 0.25)
			(net 24 "+3V3")
			(pintype "passive")
		)
	)
	(footprint "antmicro-footprints:R_0402_1005Metric"
		(layer "F.Cu")
		(at 225.025 117.5)
		(descr "Resistor SMD 0402")
		(tags "resistor SMD 0402")
		(property "Reference" "R68"
			(at -2.975 0.4 0)
			(layer "F.SilkS")
			(effects
				(font
					(size 0.7 0.7)
					(thickness 0.15)
				)
				(justify left bottom)
			)
		)
		(property "Value" "R_10k_0402"
			(at 0 1.4 0)
			(layer "F.Fab")
			(effects
				(font
					(size 0.7 0.7)
					(thickness 0.15)
				)
				(justify left bottom)
			)
		)
		(property "Description" "SMD Chip Resistor, 10 kohm, ± 1%, 62.5 mW, 0402 [1005 Metric], Thick Film, General Purpose"
			(at 0 0 0)
			(layer "F.Fab")
			(hide yes)
			(effects
				(font
					(size 1.27 1.27)
					(thickness 0.15)
				)
			)
		)
		(property "Author" "Antmicro"
			(at 0 0 0)
			(layer "F.Fab")
			(hide yes)
			(effects
				(font
					(size 1 1)
					(thickness 0.15)
				)
			)
		)
		(property "License" "Apache-2.0"
			(at 0 0 0)
			(layer "F.Fab")
			(hide yes)
			(effects
				(font
					(size 1 1)
					(thickness 0.15)
				)
			)
		)
		(property "MPN" "CR0402-FX-1002GLF"
			(at 0 0 0)
			(layer "F.Fab")
			(hide yes)
			(effects
				(font
					(size 1 1)
					(thickness 0.15)
				)
			)
		)
		(property "Manufacturer" "Bourns"
			(at 0 0 0)
			(layer "F.Fab")
			(hide yes)
			(effects
				(font
					(size 1 1)
					(thickness 0.15)
				)
			)
		)
		(property "Tolerance" "1%"
			(at 0 0 0)
			(layer "F.Fab")
			(hide yes)
			(effects
				(font
					(size 1 1)
					(thickness 0.15)
				)
			)
		)
		(property "Val" "10k"
			(at 0 0 0)
			(layer "F.Fab")
			(hide yes)
			(effects
				(font
					(size 1 1)
					(thickness 0.15)
				)
			)
		)
		(sheetname "SPI Flash + SD Card")
		(sheetfile "spi-flash.kicad_sch")
		(attr smd)
		(fp_rect
			(start -0.925 -0.47)
			(end 0.925 0.47)
			(stroke
				(width 0.05)
				(type default)
			)
			(fill no)
			(layer "F.CrtYd")
		)
		(fp_rect
			(start -0.5 -0.25)
			(end 0.5 0.25)
			(stroke
				(width 0.15)
				(type solid)
			)
			(fill no)
			(layer "F.Fab")
		)
		(pad "1" smd roundrect
			(at -0.48 0)
			(size 0.59 0.64)
			(layers "F.Cu" "F.Mask" "F.Paste")
			(roundrect_rratio 0.25)
			(net 75 "/FPGA Bank 14 & 15/SYSTEM_FLASH.~{CS}")
			(pintype "passive")
		)
		(pad "2" smd roundrect
			(at 0.48 0)
			(size 0.59 0.64)
			(layers "F.Cu" "F.Mask" "F.Paste")
			(roundrect_rratio 0.25)
			(net 24 "+3V3")
			(pintype "passive")
		)
	)
	(footprint "antmicro-footprints:C_0402_1005Metric"
		(layer "F.Cu")
		(at 207.403752 96.5615 180)
		(descr "Capacitor SMD 0402")
		(tags "capacitor SMD 0402")
		(property "Reference" "C260"
			(at 1.753752 7.1115 180)
			(layer "F.SilkS")
			(effects
				(font
					(size 0.7 0.7)
					(thickness 0.15)
				)
				(justify left bottom)
			)
		)
		(property "Value" "C_100n_0402"
			(at 0 1.169 180)
			(layer "F.Fab")
			(effects
				(font
					(size 0.7 0.7)
					(thickness 0.15)
				)
				(justify left bottom)
			)
		)
		(property "Description" "SMD Multilayer Ceramic Capacitor, 0.1 µF, 50 V, 0402 [1005 Metric], ± 10%, X5R, GRM Series"
			(at 0 0 180)
			(layer "F.Fab")
			(hide yes)
			(effects
				(font
					(size 1.27 1.27)
					(thickness 0.15)
				)
			)
		)
		(property "Author" "Antmicro"
			(at 414.807504 193.123 0)
			(layer "F.Fab")
			(hide yes)
			(effects
				(font
					(size 1 1)
					(thickness 0.15)
				)
			)
		)
		(property "Dielectric" "X5R"
			(at 414.807504 193.123 0)
			(layer "F.Fab")
			(hide yes)
			(effects
				(font
					(size 1 1)
					(thickness 0.15)
				)
			)
		)
		(property "License" "Apache-2.0"
			(at 414.807504 193.123 0)
			(layer "F.Fab")
			(hide yes)
			(effects
				(font
					(size 1 1)
					(thickness 0.15)
				)
			)
		)
		(property "MPN" "GRM155R61H104KE14D"
			(at 414.807504 193.123 0)
			(layer "F.Fab")
			(hide yes)
			(effects
				(font
					(size 1 1)
					(thickness 0.15)
				)
			)
		)
		(property "Manufacturer" "Murata"
			(at 414.807504 193.123 0)
			(layer "F.Fab")
			(hide yes)
			(effects
				(font
					(size 1 1)
					(thickness 0.15)
				)
			)
		)
		(property "Val" "100n"
			(at 414.807504 193.123 0)
			(layer "F.Fab")
			(hide yes)
			(effects
				(font
					(size 1 1)
					(thickness 0.15)
				)
			)
		)
		(property "Voltage" "50V"
			(at 414.807504 193.123 0)
			(layer "F.Fab")
			(hide yes)
			(effects
				(font
					(size 1 1)
					(thickness 0.15)
				)
			)
		)
		(sheetname "HDMI + Ethernet")
		(sheetfile "hdmi-ethernet.kicad_sch")
		(attr smd)
		(fp_rect
			(start -0.925 -0.47)
			(end 0.925 0.47)
			(stroke
				(width 0.05)
				(type default)
			)
			(fill no)
			(layer "F.CrtYd")
		)
		(fp_line
			(start 0.504 0.248)
			(end -0.494 0.248)
			(stroke
				(width 0.15)
				(type solid)
			)
			(layer "F.Fab")
		)
		(fp_line
			(start 0.504 -0.25)
			(end 0.504 0.248)
			(stroke
				(width 0.15)
				(type solid)
			)
			(layer "F.Fab")
		)
		(fp_line
			(start -0.494 0.248)
			(end -0.494 -0.25)
			(stroke
				(width 0.15)
				(type solid)
			)
			(layer "F.Fab")
		)
		(fp_line
			(start -0.494 -0.25)
			(end 0.504 -0.25)
			(stroke
				(width 0.15)
				(type solid)
			)
			(layer "F.Fab")
		)
		(pad "1" smd roundrect
			(at -0.48 0 180)
			(size 0.59 0.64)
			(layers "F.Cu" "F.Mask" "F.Paste")
			(roundrect_rratio 0.25)
			(net 1 "GND")
			(pintype "passive")
		)
		(pad "2" smd roundrect
			(at 0.48 0 180)
			(size 0.59 0.64)
			(layers "F.Cu" "F.Mask" "F.Paste")
			(roundrect_rratio 0.25)
			(net 717 "/HDMI + Ethernet/GBE_AVDDH")
			(pintype "passive")
		)
	)
	(footprint "antmicro-footprints:R_0402_1005Metric"
		(layer "F.Cu")
		(at 236.35 143.45 180)
		(descr "Resistor SMD 0402")
		(tags "resistor SMD 0402")
		(property "Reference" "R185"
			(at 1.05 -4.45 180)
			(layer "F.SilkS")
			(effects
				(font
					(size 0.7 0.7)
					(thickness 0.15)
				)
				(justify left bottom)
			)
		)
		(property "Value" "R_33R_0402"
			(at 0 1.4 180)
			(layer "F.Fab")
			(effects
				(font
					(size 0.7 0.7)
					(thickness 0.15)
				)
				(justify left bottom)
			)
		)
		(property "Description" "SMD Chip Resistor, 33 ohm, ± 1%, 62.5 mW, 0402 [1005 Metric], Thick Film, General Purpose"
			(at 0 0 180)
			(layer "F.Fab")
			(hide yes)
			(effects
				(font
					(size 1.27 1.27)
					(thickness 0.15)
				)
			)
		)
		(property "Author" "Antmicro"
			(at 472.7 286.9 0)
			(layer "F.Fab")
			(hide yes)
			(effects
				(font
					(size 1 1)
					(thickness 0.15)
				)
			)
		)
		(property "License" "Apache-2.0"
			(at 472.7 286.9 0)
			(layer "F.Fab")
			(hide yes)
			(effects
				(font
					(size 1 1)
					(thickness 0.15)
				)
			)
		)
		(property "MPN" "CR0402-FX-33R0GLF"
			(at 472.7 286.9 0)
			(layer "F.Fab")
			(hide yes)
			(effects
				(font
					(size 1 1)
					(thickness 0.15)
				)
			)
		)
		(property "Manufacturer" "Bourns"
			(at 472.7 286.9 0)
			(layer "F.Fab")
			(hide yes)
			(effects
				(font
					(size 1 1)
					(thickness 0.15)
				)
			)
		)
		(property "Tolerance" "1%"
			(at 472.7 286.9 0)
			(layer "F.Fab")
			(hide yes)
			(effects
				(font
					(size 1 1)
					(thickness 0.15)
				)
			)
		)
		(property "Val" "33R"
			(at 472.7 286.9 0)
			(layer "F.Fab")
			(hide yes)
			(effects
				(font
					(size 1 1)
					(thickness 0.15)
				)
			)
		)
		(sheetname "USB PHY")
		(sheetfile "usb-phy.kicad_sch")
		(attr smd)
		(fp_rect
			(start -0.925 -0.47)
			(end 0.925 0.47)
			(stroke
				(width 0.05)
				(type default)
			)
			(fill no)
			(layer "F.CrtYd")
		)
		(fp_rect
			(start -0.5 -0.25)
			(end 0.5 0.25)
			(stroke
				(width 0.15)
				(type solid)
			)
			(fill no)
			(layer "F.Fab")
		)
		(pad "1" smd roundrect
			(at -0.48 0 180)
			(size 0.59 0.64)
			(layers "F.Cu" "F.Mask" "F.Paste")
			(roundrect_rratio 0.25)
			(net 378 "Net-(U23-B4)")
			(pintype "passive")
		)
		(pad "2" smd roundrect
			(at 0.48 0 180)
			(size 0.59 0.64)
			(layers "F.Cu" "F.Mask" "F.Paste")
			(roundrect_rratio 0.25)
			(net 1294 "/USB_SPI.MISO")
			(pintype "passive")
		)
	)
)
